# S9S_MB_2U (Grand Teton) — schematic netlist excerpt (pin names and nets, part order shuffled) for the footprints in the layout excerpt that follows; sources: Cadence DE-HDL packaged netlist, KiCad conversion of 03242023_DA0F0TMBIJ0_F0T_Motherboard_J_brd_V01_OCP.brd

C607  Q_CAP  0.1UF 25V 10% X7R  pkg 0402  page 202 : A = PGPPA_AUX ; B = GND
R4083  Q_RES  0 5% EMPTY  pkg 0402LF  page 183 : A = E1S_0_PERST1_CLKREQ_N ; B = E1S_0_CLKREQ_N
PC1207  Q_CAP  22UF 4V 20% X6S  pkg C0805  page 300 : A = PVNN_MAIN_CPU1 ; B = GND

(kicad_pcb
	(version 20260206)
	(generator "pcbnew")
	(generator_version "10.0")
	(general
		(thickness 1.6)
		(legacy_teardrops no)
	)
	(paper "A4")
	(title_block
		(title "03242023_DA0F0TMBIJ0_F0T_Motherboard_J_brd_V01_OCP.brd")
		(comment 1 "Grand Teton / footprints 2934-2936 of 6105")
	)
	(layers
		(0 "F.Cu" signal "TOP")
		(4 "In1.Cu" signal "GND")
		(6 "In2.Cu" signal "IN1")
		(8 "In3.Cu" signal "GND1")
		(10 "In4.Cu" signal "IN2")
		(12 "In5.Cu" signal "GND2")
		(14 "In6.Cu" signal "IN3")
		(16 "In7.Cu" signal "GND3")
		(18 "In8.Cu" signal "VCC")
		(20 "In9.Cu" signal "VCC1")
		(22 "In10.Cu" signal "GND4")
		(24 "In11.Cu" signal "IN4")
		(26 "In12.Cu" signal "GND5")
		(28 "In13.Cu" signal "IN5")
		(30 "In14.Cu" signal "GND6")
		(32 "In15.Cu" signal "IN6")
		(34 "In16.Cu" signal "GND7")
		(2 "B.Cu" signal "BOTTOM")
		(9 "F.Adhes" user "F.Adhesive")
		(11 "B.Adhes" user "B.Adhesive")
		(13 "F.Paste" user "Package Geometry/Pastemask Top")
		(15 "B.Paste" user "Package Geometry/Pastemask Bottom")
		(5 "F.SilkS" user "Ref Des/Silkscreen Top")
		(7 "B.SilkS" user "Ref Des/Silkscreen Bottom")
		(1 "F.Mask" user "Board Geometry/Soldermask Top")
		(3 "B.Mask" user "Board Geometry/Soldermask Bottom")
		(17 "Dwgs.User" user "User.Drawings")
		(19 "Cmts.User" user "User.Comments")
		(21 "Eco1.User" user "User.Eco1")
		(23 "Eco2.User" user "User.Eco2")
		(25 "Edge.Cuts" user "Board Geometry/Outline")
		(27 "Margin" user)
		(31 "F.CrtYd" user "Package Geometry/Place Bound Top")
		(29 "B.CrtYd" user "Package Geometry/Place Bound Bottom")
		(35 "F.Fab" user "Ref Des/Assembly Top")
		(33 "B.Fab" user "Ref Des/Assembly Bottom")
	)
	(footprint ""
		(layer "F.Cu")
		(at 336.779108 -16.219678 -90)
		(property "Reference" "C607"
			(at 0 0 270)
			(layer "F.SilkS")
			(hide yes)
			(effects
				(font
					(size 1.27 1.27)
				)
			)
		)
		(property "Value" ""
			(at 0 0 270)
			(layer "F.Fab")
			(effects
				(font
					(size 1.27 1.27)
				)
			)
		)
		(duplicate_pad_numbers_are_jumpers no)
		(fp_line
			(start -0.7874 0.4064)
			(end -0.7874 -0.4064)
			(stroke
				(width 0.1524)
				(type default)
			)
			(layer "F.SilkS")
		)
		(fp_line
			(start 0.7874 0.4064)
			(end -0.7874 0.4064)
			(stroke
				(width 0.1524)
				(type default)
			)
			(layer "F.SilkS")
		)
		(fp_line
			(start -0.7874 -0.4064)
			(end 0.7874 -0.4064)
			(stroke
				(width 0.1524)
				(type default)
			)
			(layer "F.SilkS")
		)
		(fp_line
			(start 0.7874 -0.4064)
			(end 0.7874 0.4064)
			(stroke
				(width 0.1524)
				(type default)
			)
			(layer "F.SilkS")
		)
		(fp_line
			(start -0.67945 0.3048)
			(end -0.67945 -0.305054)
			(stroke
				(width 0.1)
				(type default)
			)
			(layer "F.Fab")
		)
		(fp_line
			(start -0.12065 0.3048)
			(end -0.67945 0.3048)
			(stroke
				(width 0.1)
				(type default)
			)
			(layer "F.Fab")
		)
		(fp_line
			(start 0.120396 0.3048)
			(end 0.120396 0.2794)
			(stroke
				(width 0.1)
				(type default)
			)
			(layer "F.Fab")
		)
		(fp_line
			(start 0.67945 0.3048)
			(end 0.120396 0.3048)
			(stroke
				(width 0.1)
				(type default)
			)
			(layer "F.Fab")
		)
		(fp_line
			(start -0.12065 0.2794)
			(end -0.12065 0.3048)
			(stroke
				(width 0.1)
				(type default)
			)
			(layer "F.Fab")
		)
		(fp_line
			(start 0.120396 0.2794)
			(end -0.12065 0.2794)
			(stroke
				(width 0.1)
				(type default)
			)
			(layer "F.Fab")
		)
		(fp_line
			(start -0.12065 -0.2794)
			(end 0.12065 -0.2794)
			(stroke
				(width 0.1)
				(type default)
			)
			(layer "F.Fab")
		)
		(fp_line
			(start 0.12065 -0.2794)
			(end 0.12065 -0.3048)
			(stroke
				(width 0.1)
				(type default)
			)
			(layer "F.Fab")
		)
		(fp_line
			(start 0.12065 -0.3048)
			(end 0.67945 -0.3048)
			(stroke
				(width 0.1)
				(type default)
			)
			(layer "F.Fab")
		)
		(fp_line
			(start 0.67945 -0.3048)
			(end 0.67945 0.3048)
			(stroke
				(width 0.1)
				(type default)
			)
			(layer "F.Fab")
		)
		(fp_line
			(start -0.67945 -0.305054)
			(end -0.12065 -0.305054)
			(stroke
				(width 0.1)
				(type default)
			)
			(layer "F.Fab")
		)
		(fp_line
			(start -0.12065 -0.305054)
			(end -0.12065 -0.2794)
			(stroke
				(width 0.1)
				(type default)
			)
			(layer "F.Fab")
		)
		(pad "1" smd circle
			(at -0.40005 0 270)
			(size 0 0)
			(layers "F.Cu" "F.Mask" "F.Paste")
			(net "PGPPA_AUX")
		)
		(pad "2" smd circle
			(at 0.40005 0 270)
			(size 0 0)
			(layers "F.Cu" "F.Mask" "F.Paste")
			(net "GND")
		)
	)
	(footprint ""
		(layer "F.Cu")
		(at 224.2312 -49.71288 180)
		(property "Reference" "R4083"
			(at 0 0 180)
			(layer "F.SilkS")
			(hide yes)
			(effects
				(font
					(size 1.27 1.27)
				)
			)
		)
		(property "Value" ""
			(at 0 0 180)
			(layer "F.Fab")
			(effects
				(font
					(size 1.27 1.27)
				)
			)
		)
		(duplicate_pad_numbers_are_jumpers no)
		(fp_line
			(start 0.7874 0.4064)
			(end -0.7874 0.4064)
			(stroke
				(width 0.1524)
				(type default)
			)
			(layer "F.SilkS")
		)
		(fp_line
			(start 0.7874 -0.4064)
			(end 0.7874 0.4064)
			(stroke
				(width 0.1524)
				(type default)
			)
			(layer "F.SilkS")
		)
		(fp_line
			(start -0.7874 0.4064)
			(end -0.7874 -0.4064)
			(stroke
				(width 0.1524)
				(type default)
			)
			(layer "F.SilkS")
		)
		(fp_line
			(start -0.7874 -0.4064)
			(end 0.7874 -0.4064)
			(stroke
				(width 0.1524)
				(type default)
			)
			(layer "F.SilkS")
		)
		(fp_line
			(start 0.67945 0.3048)
			(end 0.120396 0.3048)
			(stroke
				(width 0.1)
				(type default)
			)
			(layer "F.Fab")
		)
		(fp_line
			(start 0.67945 -0.3048)
			(end 0.67945 0.3048)
			(stroke
				(width 0.1)
				(type default)
			)
			(layer "F.Fab")
		)
		(fp_line
			(start 0.12065 -0.2794)
			(end 0.12065 -0.3048)
			(stroke
				(width 0.1)
				(type default)
			)
			(layer "F.Fab")
		)
		(fp_line
			(start 0.12065 -0.3048)
			(end 0.67945 -0.3048)
			(stroke
				(width 0.1)
				(type default)
			)
			(layer "F.Fab")
		)
		(fp_line
			(start 0.120396 0.3048)
			(end 0.120396 0.2794)
			(stroke
				(width 0.1)
				(type default)
			)
			(layer "F.Fab")
		)
		(fp_line
			(start 0.120396 0.2794)
			(end -0.12065 0.2794)
			(stroke
				(width 0.1)
				(type default)
			)
			(layer "F.Fab")
		)
		(fp_line
			(start -0.12065 0.3048)
			(end -0.67945 0.3048)
			(stroke
				(width 0.1)
				(type default)
			)
			(layer "F.Fab")
		)
		(fp_line
			(start -0.12065 0.2794)
			(end -0.12065 0.3048)
			(stroke
				(width 0.1)
				(type default)
			)
			(layer "F.Fab")
		)
		(fp_line
			(start -0.12065 -0.2794)
			(end 0.12065 -0.2794)
			(stroke
				(width 0.1)
				(type default)
			)
			(layer "F.Fab")
		)
		(fp_line
			(start -0.12065 -0.305054)
			(end -0.12065 -0.2794)
			(stroke
				(width 0.1)
				(type default)
			)
			(layer "F.Fab")
		)
		(fp_line
			(start -0.67945 0.3048)
			(end -0.67945 -0.305054)
			(stroke
				(width 0.1)
				(type default)
			)
			(layer "F.Fab")
		)
		(fp_line
			(start -0.67945 -0.305054)
			(end -0.12065 -0.305054)
			(stroke
				(width 0.1)
				(type default)
			)
			(layer "F.Fab")
		)
		(pad "1" smd circle
			(at -0.40005 0 180)
			(size 0 0)
			(layers "F.Cu" "F.Mask" "F.Paste")
			(net "E1S_0_PERST1_CLKREQ_N")
		)
		(pad "2" smd circle
			(at 0.40005 0 180)
			(size 0 0)
			(layers "F.Cu" "F.Mask" "F.Paste")
			(net "E1S_0_CLKREQ_N")
		)
	)
	(footprint ""
		(layer "F.Cu")
		(at 36.801298 -182.28564)
		(property "Reference" "PC1207"
			(at 0 0 0)
			(layer "F.SilkS")
			(hide yes)
			(effects
				(font
					(size 1.27 1.27)
				)
			)
		)
		(property "Value" ""
			(at 0 0 0)
			(layer "F.Fab")
			(effects
				(font
					(size 1.27 1.27)
				)
			)
		)
		(duplicate_pad_numbers_are_jumpers no)
		(fp_line
			(start -1.524 -0.762)
			(end 1.524 -0.762)
			(stroke
				(width 0.1524)
				(type default)
			)
			(layer "F.SilkS")
		)
		(fp_line
			(start -1.524 0.762)
			(end -1.524 -0.762)
			(stroke
				(width 0.1524)
				(type default)
			)
			(layer "F.SilkS")
		)
		(fp_line
			(start 1.524 -0.762)
			(end 1.524 0.762)
			(stroke
				(width 0.1524)
				(type default)
			)
			(layer "F.SilkS")
		)
		(fp_line
			(start 1.524 0.762)
			(end -1.524 0.762)
			(stroke
				(width 0.1524)
				(type default)
			)
			(layer "F.SilkS")
		)
		(fp_line
			(start -1.1049 -0.724916)
			(end -1.1049 0.724916)
			(stroke
				(width 0.1)
				(type default)
			)
			(layer "F.Fab")
		)
		(fp_line
			(start -1.1049 0.724916)
			(end 1.1049 0.724916)
			(stroke
				(width 0.1)
				(type default)
			)
			(layer "F.Fab")
		)
		(fp_line
			(start 1.1049 -0.724916)
			(end -1.1049 -0.724916)
			(stroke
				(width 0.1)
				(type default)
			)
			(layer "F.Fab")
		)
		(fp_line
			(start 1.1049 0.724916)
			(end 1.1049 -0.724916)
			(stroke
				(width 0.1)
				(type default)
			)
			(layer "F.Fab")
		)
		(pad "1" smd rect
			(at -0.889 0 180)
			(size 1.016 1.27)
			(layers "F.Cu" "F.Mask" "F.Paste")
			(net "PVNN_MAIN_CPU1")
		)
		(pad "2" smd rect
			(at 0.889 0 180)
			(size 1.016 1.27)
			(layers "F.Cu" "F.Mask" "F.Paste")
			(net "GND")
		)
	)
)
